(kicad_pcb
	(version 20260206)
	(generator "pcbnew")
	(generator_version "10.0")
	(general
		(thickness 1.6)
		(legacy_teardrops no)
	)
	(paper "A4")
	(title_block
		(title "Bryce Canyon_SCC_16316-1_OCP.brd")
		(comment 1 "Bryce Canyon / footprints 73-79 of 1561")
	)
	(layers
		(0 "F.Cu" signal "TOP")
		(4 "In1.Cu" signal "L2GND")
		(6 "In2.Cu" signal "L3")
		(8 "In3.Cu" signal "L4VCC")
		(10 "In4.Cu" signal "L5VCC")
		(12 "In5.Cu" signal "L6")
		(14 "In6.Cu" signal "L7GND")
		(2 "B.Cu" signal "BOTTOM")
		(9 "F.Adhes" user "F.Adhesive")
		(11 "B.Adhes" user "B.Adhesive")
		(13 "F.Paste" user "Package Geometry/Pastemask Top")
		(15 "B.Paste" user "Package Geometry/Pastemask Bottom")
		(5 "F.SilkS" user "Ref Des/Silkscreen Top")
		(7 "B.SilkS" user "Ref Des/Silkscreen Bottom")
		(1 "F.Mask" user "Board Geometry/Soldermask Top")
		(3 "B.Mask" user "Board Geometry/Soldermask Bottom")
		(17 "Dwgs.User" user "User.Drawings")
		(19 "Cmts.User" user "User.Comments")
		(21 "Eco1.User" user "User.Eco1")
		(23 "Eco2.User" user "User.Eco2")
		(25 "Edge.Cuts" user "Board Geometry/Outline")
		(27 "Margin" user)
		(31 "F.CrtYd" user "Package Geometry/Place Bound Top")
		(29 "B.CrtYd" user "Package Geometry/Place Bound Bottom")
		(35 "F.Fab" user "Ref Des/Assembly Top")
		(33 "B.Fab" user "Ref Des/Assembly Bottom")
	)
	(footprint ""
		(layer "F.Cu")
		(at 191.516 -32.0675 -90)
		(property "Reference" "TP61"
			(at 0 0 270)
			(layer "F.SilkS")
			(hide yes)
			(effects
				(font
					(size 1.27 1.27)
				)
			)
		)
		(property "Value" "TPAD28-2-GP"
			(at -0.0127 -1.6637 270)
			(unlocked yes)
			(layer "F.Fab")
			(hide yes)
			(effects
				(font
					(size 1.016 1.016)
					(thickness 0.1524)
				)
			)
		)
		(property "Device Type" "TPAD28"
			(at -0.0127 -3.1877 270)
			(unlocked yes)
			(layer "F.Fab")
			(hide yes)
			(effects
				(font
					(size 1.016 1.016)
					(thickness 0.1524)
				)
			)
		)
		(duplicate_pad_numbers_are_jumpers no)
		(fp_poly
			(pts
				(arc
					(start 0 -0.3556)
					(mid 0 0.3556)
					(end 0 -0.3556)
				)
			)
			(stroke
				(width 0)
				(type default)
			)
			(fill no)
			(layer "F.CrtYd")
		)
		(fp_poly
			(pts
				(arc
					(start 0 -0.6096)
					(mid 0 0.6096)
					(end 0 -0.6096)
				)
			)
			(stroke
				(width 0)
				(type default)
			)
			(fill no)
			(layer "F.Fab")
		)
		(pad "1" smd circle
			(at 0 0 270)
			(size 0.7112 0.7112)
			(layers "F.Cu" "F.Mask" "F.Paste")
			(net "IOC_GPIO_8")
		)
	)
	(footprint ""
		(layer "F.Cu")
		(at 172.26915 -23.557484 90)
		(property "Reference" "VIA4"
			(at 0 0 90)
			(layer "F.SilkS")
			(hide yes)
			(effects
				(font
					(size 1.27 1.27)
				)
			)
		)
		(property "Value" "85OHM-8L-1D6MM-L16L18-GP"
			(at 4.064 0.6096 90)
			(unlocked yes)
			(layer "F.Fab")
			(hide yes)
			(effects
				(font
					(size 1.016 1.016)
					(thickness 0.1524)
				)
			)
		)
		(property "Device Type" "VIA-PCIE-4P-368076"
			(at 4.064 -0.9144 90)
			(unlocked yes)
			(layer "F.Fab")
			(hide yes)
			(effects
				(font
					(size 1.016 1.016)
					(thickness 0.1524)
				)
			)
		)
		(duplicate_pad_numbers_are_jumpers no)
		(fp_rect
			(start -1.8415 0.381)
			(end 1.8415 -0.381)
			(stroke
				(width 0)
				(type default)
			)
			(fill no)
			(layer "F.CrtYd")
		)
		(fp_rect
			(start -1.8415 0.381)
			(end 1.8415 -0.381)
			(stroke
				(width 0)
				(type default)
			)
			(fill no)
			(layer "F.Fab")
		)
		(pad "1" thru_hole circle
			(at -1.4605 0 90)
			(size 0.508 0.508)
			(drill 0.254)
			(layers "*.Cu" "*.Mask")
			(remove_unused_layers no)
			(net "GND")
			(clearance 0.127)
			(thermal_gap 0.127)
		)
		(pad "2" thru_hole circle
			(at -0.4445 0 90)
			(size 0.508 0.508)
			(drill 0.254)
			(layers "*.Cu" "*.Mask")
			(remove_unused_layers no)
			(net "PCIE_COMP_TO_SCC_3_DP")
			(clearance 0.127)
			(thermal_gap 0.127)
		)
		(pad "3" thru_hole circle
			(at 0.4445 0 90)
			(size 0.508 0.508)
			(drill 0.254)
			(layers "*.Cu" "*.Mask")
			(remove_unused_layers no)
			(net "PCIE_COMP_TO_SCC_3_DN")
			(clearance 0.127)
			(thermal_gap 0.127)
		)
		(pad "4" thru_hole circle
			(at 1.4605 0 90)
			(size 0.508 0.508)
			(drill 0.254)
			(layers "*.Cu" "*.Mask")
			(remove_unused_layers no)
			(net "GND")
			(clearance 0.127)
			(thermal_gap 0.127)
		)
	)
	(footprint ""
		(layer "F.Cu")
		(at 149.666452 -44.762928 -78)
		(property "Reference" "VIA21"
			(at 0 0 282)
			(layer "F.SilkS")
			(hide yes)
			(effects
				(font
					(size 1.27 1.27)
				)
			)
		)
		(property "Value" "100OHM-8L-1D6MM-L13-GP"
			(at 3.289333 0.050849 282)
			(unlocked yes)
			(layer "F.Fab")
			(hide yes)
			(effects
				(font
					(size 1.016 1.016)
					(thickness 0.1524)
				)
			)
		)
		(property "Device Type" "VIA-PCIE-4P-409091"
			(at 3.289207 -1.473208 282)
			(unlocked yes)
			(layer "F.Fab")
			(hide yes)
			(effects
				(font
					(size 1.016 1.016)
					(thickness 0.1524)
				)
			)
		)
		(duplicate_pad_numbers_are_jumpers no)
		(fp_poly
			(pts
				(xy -2.044719 -0.457296) (xy 2.04468 -0.457296) (xy 2.044681 0.457104) (xy -2.044719 0.457104)
			)
			(stroke
				(width 0)
				(type default)
			)
			(fill no)
			(layer "F.CrtYd")
		)
		(fp_poly
			(pts
				(xy -2.044719 -0.457296) (xy 2.04468 -0.457296) (xy 2.044681 0.457104) (xy -2.044719 0.457104)
			)
			(stroke
				(width 0)
				(type default)
			)
			(fill no)
			(layer "F.Fab")
		)
		(pad "1" thru_hole circle
			(at -1.5875 0 282)
			(size 0.508 0.508)
			(drill 0.254)
			(layers "*.Cu" "*.Mask")
			(remove_unused_layers no)
			(net "GND")
			(clearance 0.2032)
			(thermal_gap 0.2032)
		)
		(pad "2" thru_hole circle
			(at -0.5715 0.000001 282)
			(size 0.508 0.508)
			(drill 0.254)
			(layers "*.Cu" "*.Mask")
			(remove_unused_layers no)
			(net "PHY_SCC_TO_IOC_C_44_DP")
			(clearance 0.2032)
			(thermal_gap 0.2032)
		)
		(pad "3" thru_hole circle
			(at 0.5715 -0.000001 282)
			(size 0.508 0.508)
			(drill 0.254)
			(layers "*.Cu" "*.Mask")
			(remove_unused_layers no)
			(net "PHY_SCC_TO_IOC_C_44_DN")
			(clearance 0.2032)
			(thermal_gap 0.2032)
		)
		(pad "4" thru_hole circle
			(at 1.5875 0 282)
			(size 0.508 0.508)
			(drill 0.254)
			(layers "*.Cu" "*.Mask")
			(remove_unused_layers no)
			(net "GND")
			(clearance 0.2032)
			(thermal_gap 0.2032)
		)
	)
	(footprint ""
		(layer "F.Cu")
		(at 86.037166 -55.248048)
		(property "Reference" "X1"
			(at 0 0 0)
			(layer "F.SilkS")
			(hide yes)
			(effects
				(font
					(size 1.27 1.27)
				)
			)
		)
		(property "Value" "XTAL-25MHZ-295-GP"
			(at -4.4958 -3.3782 0)
			(unlocked yes)
			(layer "F.Fab")
			(hide yes)
			(effects
				(font
					(size 1.016 1.016)
					(thickness 0.1524)
				)
			)
		)
		(property "Device Type" "SMD-OSC38H20"
			(at -4.4958 -4.9022 0)
			(unlocked yes)
			(layer "F.Fab")
			(hide yes)
			(effects
				(font
					(size 1.016 1.016)
					(thickness 0.1524)
				)
			)
		)
		(duplicate_pad_numbers_are_jumpers no)
		(fp_line
			(start -1.668272 1.2065)
			(end -1.668272 0.462788)
			(stroke
				(width 0.3302)
				(type default)
			)
			(layer "F.SilkS")
		)
		(fp_line
			(start -1.5748 -1.1176)
			(end 1.5748 -1.1176)
			(stroke
				(width 0.1524)
				(type default)
			)
			(layer "F.SilkS")
		)
		(fp_line
			(start -1.5748 1.1176)
			(end -1.5748 -1.1176)
			(stroke
				(width 0.1524)
				(type default)
			)
			(layer "F.SilkS")
		)
		(fp_line
			(start -0.659384 1.2065)
			(end -1.668272 1.2065)
			(stroke
				(width 0.3302)
				(type default)
			)
			(layer "F.SilkS")
		)
		(fp_line
			(start 1.5748 -1.1176)
			(end 1.5748 1.1176)
			(stroke
				(width 0.1524)
				(type default)
			)
			(layer "F.SilkS")
		)
		(fp_line
			(start 1.5748 1.1176)
			(end -1.5748 1.1176)
			(stroke
				(width 0.1524)
				(type default)
			)
			(layer "F.SilkS")
		)
		(fp_poly
			(pts
				(xy -2.286 1.1557) (xy -2.286 -0.1143) (xy -1.651 0.5207)
			)
			(stroke
				(width 0)
				(type default)
			)
			(fill yes)
			(layer "F.SilkS")
		)
		(fp_rect
			(start -1.0033 0.8001)
			(end 1.0033 -0.8001)
			(stroke
				(width 0)
				(type default)
			)
			(fill no)
			(layer "F.CrtYd")
		)
		(fp_poly
			(pts
				(xy -1.8288 1.3716) (xy -1.8288 -1.3716) (xy 1.8288 -1.3716) (xy 1.8288 -0.0127) (xy 1.0033 -0.0127)
				(xy 1.0033 -0.8001) (xy -1.0033 -0.8001) (xy -1.0033 0.8001) (xy 1.0033 0.8001) (xy 1.0033 0) (xy 1.8288 0)
				(xy 1.8288 1.3716)
			)
			(stroke
				(width 0)
				(type default)
			)
			(fill no)
			(layer "F.CrtYd")
		)
		(fp_rect
			(start -1.8288 1.3716)
			(end 1.8288 -1.3716)
			(stroke
				(width 0)
				(type default)
			)
			(fill no)
			(layer "F.Fab")
		)
		(pad "1" smd rect
			(at -0.769112 0.495046)
			(size 1.0922 0.7366)
			(layers "F.Cu" "F.Mask" "F.Paste")
			(net "EXP_REF_CLK_R_N")
		)
		(pad "2" smd rect
			(at 0.769112 0.495046)
			(size 1.0922 0.7366)
			(layers "F.Cu" "F.Mask" "F.Paste")
			(net "GND")
		)
		(pad "3" smd rect
			(at 0.769112 -0.495046)
			(size 1.0922 0.7366)
			(layers "F.Cu" "F.Mask" "F.Paste")
			(net "EXP_REF_CLK_P")
		)
		(pad "4" smd rect
			(at -0.769112 -0.495046)
			(size 1.0922 0.7366)
			(layers "F.Cu" "F.Mask" "F.Paste")
			(net "GND")
		)
		(zone
			(layer "F.Cu")
			(hatch none 0.5)
			(connect_pads
				(clearance 0)
			)
			(min_thickness 0.25)
			(keepout
				(tracks allowed)
				(vias not_allowed)
				(pads allowed)
				(copperpour not_allowed)
				(footprints allowed)
			)
			(placement
				(enabled no)
				(sheetname "")
			)
			(fill
				(thermal_gap 0.5)
				(thermal_bridge_width 0.5)
				(island_removal_mode 0)
			)
			(polygon
				(pts
					(xy 85.814154 -54.384702) (xy 85.814154 -55.121302) (xy 84.721954 -55.121302) (xy 84.721954 -55.374794)
					(xy 85.814154 -55.374794) (xy 85.814154 -56.111394) (xy 86.260178 -56.111394) (xy 86.260178 -55.374794)
					(xy 87.352378 -55.374794) (xy 87.352378 -55.121302) (xy 86.260178 -55.121302) (xy 86.260178 -54.384702)
				)
			)
		)
		(zone
			(layer "F.Cu")
			(hatch none 0.5)
			(connect_pads
				(clearance 0)
			)
			(min_thickness 0.25)
			(keepout
				(tracks not_allowed)
				(vias allowed)
				(pads allowed)
				(copperpour not_allowed)
				(footprints allowed)
			)
			(placement
				(enabled no)
				(sheetname "")
			)
			(fill
				(thermal_gap 0.5)
				(thermal_bridge_width 0.5)
				(island_removal_mode 0)
			)
			(polygon
				(pts
					(xy 85.814154 -54.384702) (xy 85.814154 -55.121302) (xy 84.721954 -55.121302) (xy 84.721954 -55.374794)
					(xy 85.814154 -55.374794) (xy 85.814154 -56.111394) (xy 86.260178 -56.111394) (xy 86.260178 -55.374794)
					(xy 87.352378 -55.374794) (xy 87.352378 -55.121302) (xy 86.260178 -55.121302) (xy 86.260178 -54.384702)
				)
			)
		)
	)
	(footprint ""
		(layer "F.Cu")
		(at 165.717474 -79.904082 180)
		(property "Reference" "L32"
			(at 0 0 180)
			(layer "F.SilkS")
			(hide yes)
			(effects
				(font
					(size 1.27 1.27)
				)
			)
		)
		(property "Value" "BLM41PG600-GP"
			(at -3.690874 -7.441184 180)
			(unlocked yes)
			(layer "F.Fab")
			(hide yes)
			(effects
				(font
					(size 1.016 1.016)
					(thickness 0.1524)
				)
			)
		)
		(property "Device Type" "L451616H71"
			(at -3.690874 -5.917184 180)
			(unlocked yes)
			(layer "F.Fab")
			(hide yes)
			(effects
				(font
					(size 1.016 1.016)
					(thickness 0.1524)
				)
			)
		)
		(duplicate_pad_numbers_are_jumpers no)
		(fp_line
			(start 2.8702 1.2954)
			(end 2.8702 -1.2954)
			(stroke
				(width 0.1524)
				(type default)
			)
			(layer "F.SilkS")
		)
		(fp_line
			(start 2.8702 1.2954)
			(end 2.8702 -1.2954)
			(stroke
				(width 0.1524)
				(type default)
			)
			(layer "F.SilkS")
		)
		(fp_line
			(start 2.8702 -1.2954)
			(end -2.8702 -1.2954)
			(stroke
				(width 0.1524)
				(type default)
			)
			(layer "F.SilkS")
		)
		(fp_line
			(start 2.8702 -1.2954)
			(end -2.8702 -1.2954)
			(stroke
				(width 0.1524)
				(type default)
			)
			(layer "F.SilkS")
		)
		(fp_line
			(start -2.8702 1.2954)
			(end 2.8702 1.2954)
			(stroke
				(width 0.1524)
				(type default)
			)
			(layer "F.SilkS")
		)
		(fp_line
			(start -2.8702 1.2954)
			(end 2.8702 1.2954)
			(stroke
				(width 0.1524)
				(type default)
			)
			(layer "F.SilkS")
		)
		(fp_line
			(start -2.8702 -1.2954)
			(end -2.8702 1.2954)
			(stroke
				(width 0.1524)
				(type default)
			)
			(layer "F.SilkS")
		)
		(fp_line
			(start -2.8702 -1.2954)
			(end -2.8702 1.2954)
			(stroke
				(width 0.1524)
				(type default)
			)
			(layer "F.SilkS")
		)
		(fp_poly
			(pts
				(xy -2.8702 1.2954) (xy 2.8702 1.2954) (xy 2.8702 -1.2954) (xy -2.8702 -1.2954)
			)
			(stroke
				(width 0)
				(type default)
			)
			(fill no)
			(layer "F.CrtYd")
		)
		(fp_poly
			(pts
				(xy -2.8702 1.2954) (xy 2.8702 1.2954) (xy 2.8702 -1.2954) (xy -2.8702 -1.2954)
			)
			(stroke
				(width 0)
				(type default)
			)
			(fill no)
			(layer "F.Fab")
		)
		(pad "1" smd rect
			(at -1.9685 0 180)
			(size 1.3716 1.8796)
			(layers "F.Cu" "F.Mask" "F.Paste")
			(net "P12V_STBY_SCC")
		)
		(pad "2" smd rect
			(at 1.9685 0 180)
			(size 1.3716 1.8796)
			(layers "F.Cu" "F.Mask" "F.Paste")
			(net "P12V_SYBY_VDD_U6")
		)
	)
	(footprint ""
		(layer "F.Cu")
		(at 149.521418 -54.942232 -78)
		(property "Reference" "VIA24"
			(at 0 0 282)
			(layer "F.SilkS")
			(hide yes)
			(effects
				(font
					(size 1.27 1.27)
				)
			)
		)
		(property "Value" "100OHM-8L-1D6MM-L13-GP"
			(at 3.289333 0.050849 282)
			(unlocked yes)
			(layer "F.Fab")
			(hide yes)
			(effects
				(font
					(size 1.016 1.016)
					(thickness 0.1524)
				)
			)
		)
		(property "Device Type" "VIA-PCIE-4P-409091"
			(at 3.289207 -1.473208 282)
			(unlocked yes)
			(layer "F.Fab")
			(hide yes)
			(effects
				(font
					(size 1.016 1.016)
					(thickness 0.1524)
				)
			)
		)
		(duplicate_pad_numbers_are_jumpers no)
		(fp_poly
			(pts
				(xy -2.044719 -0.457296) (xy 2.04468 -0.457296) (xy 2.044681 0.457104) (xy -2.044719 0.457104)
			)
			(stroke
				(width 0)
				(type default)
			)
			(fill no)
			(layer "F.CrtYd")
		)
		(fp_poly
			(pts
				(xy -2.044719 -0.457296) (xy 2.04468 -0.457296) (xy 2.044681 0.457104) (xy -2.044719 0.457104)
			)
			(stroke
				(width 0)
				(type default)
			)
			(fill no)
			(layer "F.Fab")
		)
		(pad "1" thru_hole circle
			(at -1.5875 0 282)
			(size 0.508 0.508)
			(drill 0.254)
			(layers "*.Cu" "*.Mask")
			(remove_unused_layers no)
			(net "GND")
			(clearance 0.2032)
			(thermal_gap 0.2032)
		)
		(pad "2" thru_hole circle
			(at -0.5715 0.000001 282)
			(size 0.508 0.508)
			(drill 0.254)
			(layers "*.Cu" "*.Mask")
			(remove_unused_layers no)
			(net "PHY_SCC_TO_IOC_C_47_DP")
			(clearance 0.2032)
			(thermal_gap 0.2032)
		)
		(pad "3" thru_hole circle
			(at 0.5715 -0.000001 282)
			(size 0.508 0.508)
			(drill 0.254)
			(layers "*.Cu" "*.Mask")
			(remove_unused_layers no)
			(net "PHY_SCC_TO_IOC_C_47_DN")
			(clearance 0.2032)
			(thermal_gap 0.2032)
		)
		(pad "4" thru_hole circle
			(at 1.5875 0 282)
			(size 0.508 0.508)
			(drill 0.254)
			(layers "*.Cu" "*.Mask")
			(remove_unused_layers no)
			(net "GND")
			(clearance 0.2032)
			(thermal_gap 0.2032)
		)
	)
	(footprint ""
		(layer "F.Cu")
		(at 65.278 -24.13 -90)
		(property "Reference" "R582"
			(at 0 0 270)
			(layer "F.SilkS")
			(hide yes)
			(effects
				(font
					(size 1.27 1.27)
				)
			)
		)
		(property "Value" "0R2J-2-GP"
			(at 0.064008 -3.993896 270)
			(unlocked yes)
			(layer "F.Fab")
			(hide yes)
			(effects
				(font
					(size 1.016 1.016)
					(thickness 0.1524)
				)
			)
		)
		(property "Device Type" "R402H16"
			(at 0.064008 -5.517896 270)
			(unlocked yes)
			(layer "F.Fab")
			(hide yes)
			(effects
				(font
					(size 1.016 1.016)
					(thickness 0.1524)
				)
			)
		)
		(duplicate_pad_numbers_are_jumpers no)
		(fp_line
			(start -0.508 -0.9398)
			(end -0.508 0.9398)
			(stroke
				(width 0.1524)
				(type default)
			)
			(layer "F.SilkS")
		)
		(fp_line
			(start 0.508 -0.9398)
			(end -0.508 -0.9398)
			(stroke
				(width 0.1524)
				(type default)
			)
			(layer "F.SilkS")
		)
		(fp_rect
			(start -0.508 0.9398)
			(end 0.508 -0.9398)
			(stroke
				(width 0)
				(type default)
			)
			(fill no)
			(layer "F.CrtYd")
		)
		(fp_rect
			(start -0.508 0.9398)
			(end 0.508 -0.9398)
			(stroke
				(width 0)
				(type default)
			)
			(fill no)
			(layer "F.Fab")
		)
		(pad "1" smd custom
			(at 0 -0.4445 270)
			(size 0.1397 0.1397)
			(layers "F.Cu" "F.Mask" "F.Paste")
			(net "SCC_FULL_PWR_EN")
			(options
				(clearance outline)
				(anchor circle)
			)
			(primitives
				(gr_poly
					(pts
						(arc
							(start -0.1778 -0.2794)
							(mid -0.249642 -0.249642)
							(end -0.2794 -0.1778)
						)
						(arc
							(start -0.2794 0.1778)
							(mid -0.249642 0.249642)
							(end -0.1778 0.2794)
						)
						(arc
							(start 0.1778 0.2794)
							(mid 0.249642 0.249642)
							(end 0.2794 0.1778)
						)
						(arc
							(start 0.2794 -0.1778)
							(mid 0.249642 -0.249642)
							(end 0.1778 -0.2794)
						)
					)
					(width 0)
					(fill yes)
				)
			)
		)
		(pad "2" smd custom
			(at 0 0.4445 270)
			(size 0.1397 0.1397)
			(layers "F.Cu" "F.Mask" "F.Paste")
			(net "SCC_FULL_PWR_EN_U49")
			(options
				(clearance outline)
				(anchor circle)
			)
			(primitives
				(gr_poly
					(pts
						(arc
							(start -0.1778 -0.2794)
							(mid -0.249642 -0.249642)
							(end -0.2794 -0.1778)
						)
						(arc
							(start -0.2794 0.1778)
							(mid -0.249642 0.249642)
							(end -0.1778 0.2794)
						)
						(arc
							(start 0.1778 0.2794)
							(mid 0.249642 0.249642)
							(end 0.2794 0.1778)
						)
						(arc
							(start 0.2794 -0.1778)
							(mid 0.249642 -0.249642)
							(end 0.1778 -0.2794)
						)
					)
					(width 0)
					(fill yes)
				)
			)
		)
	)
)
